(kicad_pcb
	(version 20221018)
	(generator pcbnew)
	(general
    (thickness 1.518)
  )
	(paper "A4")
	(title_block
    (title "Kria K26 Devboard")
    (date "2024-03-26")
    (rev "1.2.5")
    (comment 1 "www.antmicro.com")
    (comment 2 "Antmicro Ltd.")
		(comment 9 "footprints 489-498 of 660")
	)
	(layers
    (0 "F.Cu" mixed)
    (1 "In1.Cu" power)
    (2 "In2.Cu" mixed)
    (3 "In3.Cu" power)
    (4 "In4.Cu" mixed)
    (5 "In5.Cu" power)
    (6 "In6.Cu" mixed)
    (31 "B.Cu" power)
    (32 "B.Adhes" user "B.Adhesive")
    (33 "F.Adhes" user "F.Adhesive")
    (34 "B.Paste" user)
    (35 "F.Paste" user)
    (36 "B.SilkS" user "B.Silkscreen")
    (37 "F.SilkS" user "F.Silkscreen")
    (38 "B.Mask" user)
    (39 "F.Mask" user)
    (40 "Dwgs.User" user "User.Drawings")
    (41 "Cmts.User" user "User.Comments")
    (42 "Eco1.User" user "User.Eco1")
    (43 "Eco2.User" user "User.Eco2")
    (44 "Edge.Cuts" user)
    (45 "Margin" user)
    (46 "B.CrtYd" user "B.Courtyard")
    (47 "F.CrtYd" user "F.Courtyard")
    (48 "B.Fab" user)
    (49 "F.Fab" user)
  )
	(footprint "kria-k26-devboard-footprints:C_0402_1005Metric" (layer "B.Cu")
    (at 150.5 121.6 90)
    (descr "Capacitor SMD 0402")
    (tags "capacitor SMD 0402")
    (property "Author" "Antmicro")
    (property "Dielectric" "X5R")
    (property "License" "Apache-2.0")
    (property "MPN" "GRM155R61H104KE14D")
    (property "Manufacturer" "Murata")
    (property "Sheetfile" "debug.kicad_sch")
    (property "Sheetname" "Debug and JTAG")
    (property "Val" "100n")
    (property "Voltage" "50V")
    (property "ki_description" " ")
    (attr smd)
    (fp_text reference "C151" (at 1.26 4.35 270) (layer "B.SilkS")
        (effects (font (size 0.7 0.7) (thickness 0.15)) (justify left bottom mirror))
    )
    (fp_text value "C_100n_0402" (at 0 -1.4 270) (layer "B.Fab") hide
        (effects (font (size 0.7 0.7) (thickness 0.15)) (justify left bottom mirror))
    )
    (fp_text user "Author: Antmicro" (at -0.932 -4.17 270) (layer "B.Fab") hide
        (effects (font (size 0.7 0.7) (thickness 0.15)) (justify left bottom mirror))
    )
    (fp_text user "${REFERENCE}" (at -0.932 -3.168 270) (layer "B.Fab") hide
        (effects (font (size 0.7 0.7) (thickness 0.15)) (justify left bottom mirror))
    )
    (fp_text user "License: Apache-2.0" (at -0.932 -5.17 270) (layer "B.Fab") hide
        (effects (font (size 0.7 0.7) (thickness 0.15)) (justify left bottom mirror))
    )
    (fp_rect (start -0.94 0.47) (end 0.94 -0.47)
      (stroke (width 0.05) (type solid)) (fill none) (layer "B.CrtYd"))
    (fp_rect (start -0.499 0.249) (end 0.499 -0.249)
      (stroke (width 0.15) (type solid)) (fill none) (layer "B.Fab"))
    (pad "1" smd roundrect (at -0.484 0 90) (size 0.59 0.64) (layers "B.Cu" "B.Paste" "B.Mask") (roundrect_rratio 0.25)
      (net 132 "/Debug and JTAG/USB_1V2") (pintype "passive"))
    (pad "2" smd roundrect (at 0.484 0 90) (size 0.59 0.64) (layers "B.Cu" "B.Paste" "B.Mask") (roundrect_rratio 0.25)
      (net 1 "GND") (pintype "passive"))
  )
	(footprint "kria-k26-devboard-footprints:C_0402_1005Metric" (layer "B.Cu")
    (at 139.02 122.09 90)
    (descr "Capacitor SMD 0402")
    (tags "capacitor SMD 0402")
    (property "Author" "Antmicro")
    (property "Dielectric" "X5R")
    (property "License" "Apache-2.0")
    (property "MPN" "GRM155R61H104KE14D")
    (property "Manufacturer" "Murata")
    (property "Sheetfile" "debug.kicad_sch")
    (property "Sheetname" "Debug and JTAG")
    (property "Val" "100n")
    (property "Voltage" "50V")
    (property "ki_description" " ")
    (attr smd)
    (fp_text reference "C168" (at 1.24 2.245 270) (layer "B.SilkS")
        (effects (font (size 0.7 0.7) (thickness 0.15)) (justify left bottom mirror))
    )
    (fp_text value "C_100n_0402" (at 0 -1.4 270) (layer "B.Fab") hide
        (effects (font (size 0.7 0.7) (thickness 0.15)) (justify left bottom mirror))
    )
    (fp_text user "License: Apache-2.0" (at -0.932 -5.17 270) (layer "B.Fab") hide
        (effects (font (size 0.7 0.7) (thickness 0.15)) (justify left bottom mirror))
    )
    (fp_text user "Author: Antmicro" (at -0.932 -4.17 270) (layer "B.Fab") hide
        (effects (font (size 0.7 0.7) (thickness 0.15)) (justify left bottom mirror))
    )
    (fp_text user "${REFERENCE}" (at -0.932 -3.168 270) (layer "B.Fab") hide
        (effects (font (size 0.7 0.7) (thickness 0.15)) (justify left bottom mirror))
    )
    (fp_rect (start -0.94 0.47) (end 0.94 -0.47)
      (stroke (width 0.05) (type solid)) (fill none) (layer "B.CrtYd"))
    (fp_rect (start -0.499 0.249) (end 0.499 -0.249)
      (stroke (width 0.15) (type solid)) (fill none) (layer "B.Fab"))
    (pad "1" smd roundrect (at -0.484 0 90) (size 0.59 0.64) (layers "B.Cu" "B.Paste" "B.Mask") (roundrect_rratio 0.25)
      (net 17 "PS_1V8") (pintype "passive"))
    (pad "2" smd roundrect (at 0.484 0 90) (size 0.59 0.64) (layers "B.Cu" "B.Paste" "B.Mask") (roundrect_rratio 0.25)
      (net 1 "GND") (pintype "passive"))
  )
	(footprint "kria-k26-devboard-footprints:C_0402_1005Metric" (layer "B.Cu")
    (at 138.77 117.85 90)
    (descr "Capacitor SMD 0402")
    (tags "capacitor SMD 0402")
    (property "Author" "Antmicro")
    (property "Dielectric" "X5R")
    (property "License" "Apache-2.0")
    (property "MPN" "GRM155R61H104KE14D")
    (property "Manufacturer" "Murata")
    (property "Sheetfile" "debug.kicad_sch")
    (property "Sheetname" "Debug and JTAG")
    (property "Val" "100n")
    (property "Voltage" "50V")
    (property "ki_description" " ")
    (attr smd)
    (fp_text reference "C169" (at 1.47 -1.505 270) (layer "B.SilkS")
        (effects (font (size 0.7 0.7) (thickness 0.15)) (justify left bottom mirror))
    )
    (fp_text value "C_100n_0402" (at 0 -1.4 270) (layer "B.Fab") hide
        (effects (font (size 0.7 0.7) (thickness 0.15)) (justify left bottom mirror))
    )
    (fp_text user "${REFERENCE}" (at -0.932 -3.168 270) (layer "B.Fab") hide
        (effects (font (size 0.7 0.7) (thickness 0.15)) (justify left bottom mirror))
    )
    (fp_text user "Author: Antmicro" (at -0.932 -4.17 270) (layer "B.Fab") hide
        (effects (font (size 0.7 0.7) (thickness 0.15)) (justify left bottom mirror))
    )
    (fp_text user "License: Apache-2.0" (at -0.932 -5.17 270) (layer "B.Fab") hide
        (effects (font (size 0.7 0.7) (thickness 0.15)) (justify left bottom mirror))
    )
    (fp_rect (start -0.94 0.47) (end 0.94 -0.47)
      (stroke (width 0.05) (type solid)) (fill none) (layer "B.CrtYd"))
    (fp_rect (start -0.499 0.249) (end 0.499 -0.249)
      (stroke (width 0.15) (type solid)) (fill none) (layer "B.Fab"))
    (pad "1" smd roundrect (at -0.484 0 90) (size 0.59 0.64) (layers "B.Cu" "B.Paste" "B.Mask") (roundrect_rratio 0.25)
      (net 17 "PS_1V8") (pintype "passive"))
    (pad "2" smd roundrect (at 0.484 0 90) (size 0.59 0.64) (layers "B.Cu" "B.Paste" "B.Mask") (roundrect_rratio 0.25)
      (net 1 "GND") (pintype "passive"))
  )
	(footprint "kria-k26-devboard-footprints:C_0402_1005Metric" (layer "B.Cu")
    (at 139.73 117.85 90)
    (descr "Capacitor SMD 0402")
    (tags "capacitor SMD 0402")
    (property "Author" "Antmicro")
    (property "Dielectric" "X5R")
    (property "License" "Apache-2.0")
    (property "MPN" "GRM155R61H104KE14D")
    (property "Manufacturer" "Murata")
    (property "Sheetfile" "debug.kicad_sch")
    (property "Sheetname" "Debug and JTAG")
    (property "Val" "100n")
    (property "Voltage" "50V")
    (property "ki_description" " ")
    (attr smd)
    (fp_text reference "C163" (at 1.47 -1.505 270) (layer "B.SilkS")
        (effects (font (size 0.7 0.7) (thickness 0.15)) (justify left bottom mirror))
    )
    (fp_text value "C_100n_0402" (at 0 -1.4 270) (layer "B.Fab") hide
        (effects (font (size 0.7 0.7) (thickness 0.15)) (justify left bottom mirror))
    )
    (fp_text user "Author: Antmicro" (at -0.932 -4.17 270) (layer "B.Fab") hide
        (effects (font (size 0.7 0.7) (thickness 0.15)) (justify left bottom mirror))
    )
    (fp_text user "${REFERENCE}" (at -0.932 -3.168 270) (layer "B.Fab") hide
        (effects (font (size 0.7 0.7) (thickness 0.15)) (justify left bottom mirror))
    )
    (fp_text user "License: Apache-2.0" (at -0.932 -5.17 270) (layer "B.Fab") hide
        (effects (font (size 0.7 0.7) (thickness 0.15)) (justify left bottom mirror))
    )
    (fp_rect (start -0.94 0.47) (end 0.94 -0.47)
      (stroke (width 0.05) (type solid)) (fill none) (layer "B.CrtYd"))
    (fp_rect (start -0.499 0.249) (end 0.499 -0.249)
      (stroke (width 0.15) (type solid)) (fill none) (layer "B.Fab"))
    (pad "1" smd roundrect (at -0.484 0 90) (size 0.59 0.64) (layers "B.Cu" "B.Paste" "B.Mask") (roundrect_rratio 0.25)
      (net 138 "/Debug and JTAG/USB_3V3") (pintype "passive"))
    (pad "2" smd roundrect (at 0.484 0 90) (size 0.59 0.64) (layers "B.Cu" "B.Paste" "B.Mask") (roundrect_rratio 0.25)
      (net 1 "GND") (pintype "passive"))
  )
	(footprint "kria-k26-devboard-footprints:C_0402_1005Metric" (layer "B.Cu")
    (at 151.58 119.86 180)
    (descr "Capacitor SMD 0402")
    (tags "capacitor SMD 0402")
    (property "Author" "Antmicro")
    (property "Dielectric" "X5R")
    (property "License" "Apache-2.0")
    (property "MPN" "GRM155R61H104KE14D")
    (property "Manufacturer" "Murata")
    (property "Sheetfile" "debug.kicad_sch")
    (property "Sheetname" "Debug and JTAG")
    (property "Val" "100n")
    (property "Voltage" "50V")
    (property "ki_description" " ")
    (attr smd)
    (fp_text reference "C144" (at -3.69 -0.38) (layer "B.SilkS")
        (effects (font (size 0.7 0.7) (thickness 0.15)) (justify left bottom mirror))
    )
    (fp_text value "C_100n_0402" (at 0 -1.4) (layer "B.Fab") hide
        (effects (font (size 0.7 0.7) (thickness 0.15)) (justify left bottom mirror))
    )
    (fp_text user "License: Apache-2.0" (at -0.932 -5.17) (layer "B.Fab") hide
        (effects (font (size 0.7 0.7) (thickness 0.15)) (justify left bottom mirror))
    )
    (fp_text user "Author: Antmicro" (at -0.932 -4.17) (layer "B.Fab") hide
        (effects (font (size 0.7 0.7) (thickness 0.15)) (justify left bottom mirror))
    )
    (fp_text user "${REFERENCE}" (at -0.932 -3.168) (layer "B.Fab") hide
        (effects (font (size 0.7 0.7) (thickness 0.15)) (justify left bottom mirror))
    )
    (fp_rect (start -0.94 0.47) (end 0.94 -0.47)
      (stroke (width 0.05) (type solid)) (fill none) (layer "B.CrtYd"))
    (fp_rect (start -0.499 0.249) (end 0.499 -0.249)
      (stroke (width 0.15) (type solid)) (fill none) (layer "B.Fab"))
    (pad "1" smd roundrect (at -0.484 0 180) (size 0.59 0.64) (layers "B.Cu" "B.Paste" "B.Mask") (roundrect_rratio 0.25)
      (net 138 "/Debug and JTAG/USB_3V3") (pintype "passive"))
    (pad "2" smd roundrect (at 0.484 0 180) (size 0.59 0.64) (layers "B.Cu" "B.Paste" "B.Mask") (roundrect_rratio 0.25)
      (net 1 "GND") (pintype "passive"))
  )
	(footprint "kria-k26-devboard-footprints:C_0402_1005Metric" (layer "B.Cu")
    (at 151.58 117.86 180)
    (descr "Capacitor SMD 0402")
    (tags "capacitor SMD 0402")
    (property "Author" "Antmicro")
    (property "Dielectric" "X5R")
    (property "License" "Apache-2.0")
    (property "MPN" "GRM155R61H104KE14D")
    (property "Manufacturer" "Murata")
    (property "Sheetfile" "debug.kicad_sch")
    (property "Sheetname" "Debug and JTAG")
    (property "Val" "100n")
    (property "Voltage" "50V")
    (property "ki_description" " ")
    (attr smd)
    (fp_text reference "C145" (at -3.7 -0.37) (layer "B.SilkS")
        (effects (font (size 0.7 0.7) (thickness 0.15)) (justify left bottom mirror))
    )
    (fp_text value "C_100n_0402" (at 0 -1.4) (layer "B.Fab") hide
        (effects (font (size 0.7 0.7) (thickness 0.15)) (justify left bottom mirror))
    )
    (fp_text user "${REFERENCE}" (at -0.932 -3.168) (layer "B.Fab") hide
        (effects (font (size 0.7 0.7) (thickness 0.15)) (justify left bottom mirror))
    )
    (fp_text user "License: Apache-2.0" (at -0.932 -5.17) (layer "B.Fab") hide
        (effects (font (size 0.7 0.7) (thickness 0.15)) (justify left bottom mirror))
    )
    (fp_text user "Author: Antmicro" (at -0.932 -4.17) (layer "B.Fab") hide
        (effects (font (size 0.7 0.7) (thickness 0.15)) (justify left bottom mirror))
    )
    (fp_rect (start -0.94 0.47) (end 0.94 -0.47)
      (stroke (width 0.05) (type solid)) (fill none) (layer "B.CrtYd"))
    (fp_rect (start -0.499 0.249) (end 0.499 -0.249)
      (stroke (width 0.15) (type solid)) (fill none) (layer "B.Fab"))
    (pad "1" smd roundrect (at -0.484 0 180) (size 0.59 0.64) (layers "B.Cu" "B.Paste" "B.Mask") (roundrect_rratio 0.25)
      (net 132 "/Debug and JTAG/USB_1V2") (pintype "passive"))
    (pad "2" smd roundrect (at 0.484 0 180) (size 0.59 0.64) (layers "B.Cu" "B.Paste" "B.Mask") (roundrect_rratio 0.25)
      (net 1 "GND") (pintype "passive"))
  )
	(footprint "kria-k26-devboard-footprints:C_0402_1005Metric" (layer "B.Cu")
    (at 147.5 121.66 90)
    (descr "Capacitor SMD 0402")
    (tags "capacitor SMD 0402")
    (property "Author" "Antmicro")
    (property "Dielectric" "X5R")
    (property "License" "Apache-2.0")
    (property "MPN" "GRM155R61H104KE14D")
    (property "Manufacturer" "Murata")
    (property "Sheetfile" "debug.kicad_sch")
    (property "Sheetname" "Debug and JTAG")
    (property "Val" "100n")
    (property "Voltage" "50V")
    (property "ki_description" " ")
    (attr smd)
    (fp_text reference "C143" (at 1.26 4.35 270) (layer "B.SilkS")
        (effects (font (size 0.7 0.7) (thickness 0.15)) (justify left bottom mirror))
    )
    (fp_text value "C_100n_0402" (at 0 -1.4 270) (layer "B.Fab") hide
        (effects (font (size 0.7 0.7) (thickness 0.15)) (justify left bottom mirror))
    )
    (fp_text user "${REFERENCE}" (at -0.932 -3.168 270) (layer "B.Fab") hide
        (effects (font (size 0.7 0.7) (thickness 0.15)) (justify left bottom mirror))
    )
    (fp_text user "License: Apache-2.0" (at -0.932 -5.17 270) (layer "B.Fab") hide
        (effects (font (size 0.7 0.7) (thickness 0.15)) (justify left bottom mirror))
    )
    (fp_text user "Author: Antmicro" (at -0.932 -4.17 270) (layer "B.Fab") hide
        (effects (font (size 0.7 0.7) (thickness 0.15)) (justify left bottom mirror))
    )
    (fp_rect (start -0.94 0.47) (end 0.94 -0.47)
      (stroke (width 0.05) (type solid)) (fill none) (layer "B.CrtYd"))
    (fp_rect (start -0.499 0.249) (end 0.499 -0.249)
      (stroke (width 0.15) (type solid)) (fill none) (layer "B.Fab"))
    (pad "1" smd roundrect (at -0.484 0 90) (size 0.59 0.64) (layers "B.Cu" "B.Paste" "B.Mask") (roundrect_rratio 0.25)
      (net 132 "/Debug and JTAG/USB_1V2") (pintype "passive"))
    (pad "2" smd roundrect (at 0.484 0 90) (size 0.59 0.64) (layers "B.Cu" "B.Paste" "B.Mask") (roundrect_rratio 0.25)
      (net 1 "GND") (pintype "passive"))
  )
	(footprint "kria-k26-devboard-footprints:C_0402_1005Metric" (layer "B.Cu")
    (at 144.88 118.8)
    (descr "Capacitor SMD 0402")
    (tags "capacitor SMD 0402")
    (property "Author" "Antmicro")
    (property "Dielectric" "X5R")
    (property "License" "Apache-2.0")
    (property "MPN" "GRM155R61H104KE14D")
    (property "Manufacturer" "Murata")
    (property "Sheetfile" "debug.kicad_sch")
    (property "Sheetname" "Debug and JTAG")
    (property "Val" "100n")
    (property "Voltage" "50V")
    (property "ki_description" " ")
    (attr smd)
    (fp_text reference "C140" (at -0.88 0.38 180) (layer "B.SilkS")
        (effects (font (size 0.7 0.7) (thickness 0.15)) (justify left bottom mirror))
    )
    (fp_text value "C_100n_0402" (at 0 -1.4 180) (layer "B.Fab") hide
        (effects (font (size 0.7 0.7) (thickness 0.15)) (justify left bottom mirror))
    )
    (fp_text user "License: Apache-2.0" (at -0.932 -5.17 180) (layer "B.Fab") hide
        (effects (font (size 0.7 0.7) (thickness 0.15)) (justify left bottom mirror))
    )
    (fp_text user "Author: Antmicro" (at -0.932 -4.17 180) (layer "B.Fab") hide
        (effects (font (size 0.7 0.7) (thickness 0.15)) (justify left bottom mirror))
    )
    (fp_text user "${REFERENCE}" (at -0.932 -3.168 180) (layer "B.Fab") hide
        (effects (font (size 0.7 0.7) (thickness 0.15)) (justify left bottom mirror))
    )
    (fp_rect (start -0.94 0.47) (end 0.94 -0.47)
      (stroke (width 0.05) (type solid)) (fill none) (layer "B.CrtYd"))
    (fp_rect (start -0.499 0.249) (end 0.499 -0.249)
      (stroke (width 0.15) (type solid)) (fill none) (layer "B.Fab"))
    (pad "1" smd roundrect (at -0.484 0) (size 0.59 0.64) (layers "B.Cu" "B.Paste" "B.Mask") (roundrect_rratio 0.25)
      (net 138 "/Debug and JTAG/USB_3V3") (pintype "passive"))
    (pad "2" smd roundrect (at 0.484 0) (size 0.59 0.64) (layers "B.Cu" "B.Paste" "B.Mask") (roundrect_rratio 0.25)
      (net 1 "GND") (pintype "passive"))
  )
	(footprint "kria-k26-devboard-footprints:C_0402_1005Metric" (layer "B.Cu")
    (at 139.98 122.09 90)
    (descr "Capacitor SMD 0402")
    (tags "capacitor SMD 0402")
    (property "Author" "Antmicro")
    (property "Dielectric" "X5R")
    (property "License" "Apache-2.0")
    (property "MPN" "GRM155R61H104KE14D")
    (property "Manufacturer" "Murata")
    (property "Sheetfile" "debug.kicad_sch")
    (property "Sheetname" "Debug and JTAG")
    (property "Val" "100n")
    (property "Voltage" "50V")
    (property "ki_description" " ")
    (attr smd)
    (fp_text reference "C162" (at 1.24 2.245 270) (layer "B.SilkS")
        (effects (font (size 0.7 0.7) (thickness 0.15)) (justify left bottom mirror))
    )
    (fp_text value "C_100n_0402" (at 0 -1.4 270) (layer "B.Fab") hide
        (effects (font (size 0.7 0.7) (thickness 0.15)) (justify left bottom mirror))
    )
    (fp_text user "License: Apache-2.0" (at -0.932 -5.17 270) (layer "B.Fab") hide
        (effects (font (size 0.7 0.7) (thickness 0.15)) (justify left bottom mirror))
    )
    (fp_text user "Author: Antmicro" (at -0.932 -4.17 270) (layer "B.Fab") hide
        (effects (font (size 0.7 0.7) (thickness 0.15)) (justify left bottom mirror))
    )
    (fp_text user "${REFERENCE}" (at -0.932 -3.168 270) (layer "B.Fab") hide
        (effects (font (size 0.7 0.7) (thickness 0.15)) (justify left bottom mirror))
    )
    (fp_rect (start -0.94 0.47) (end 0.94 -0.47)
      (stroke (width 0.05) (type solid)) (fill none) (layer "B.CrtYd"))
    (fp_rect (start -0.499 0.249) (end 0.499 -0.249)
      (stroke (width 0.15) (type solid)) (fill none) (layer "B.Fab"))
    (pad "1" smd roundrect (at -0.484 0 90) (size 0.59 0.64) (layers "B.Cu" "B.Paste" "B.Mask") (roundrect_rratio 0.25)
      (net 138 "/Debug and JTAG/USB_3V3") (pintype "passive"))
    (pad "2" smd roundrect (at 0.484 0 90) (size 0.59 0.64) (layers "B.Cu" "B.Paste" "B.Mask") (roundrect_rratio 0.25)
      (net 1 "GND") (pintype "passive"))
  )
	(footprint "kria-k26-devboard-footprints:C_0402_1005Metric" (layer "B.Cu")
    (at 151.685 113.2 180)
    (descr "Capacitor SMD 0402")
    (tags "capacitor SMD 0402")
    (property "Author" "Antmicro")
    (property "Dielectric" "")
    (property "License" "Apache-2.0")
    (property "MPN" "GRM155R61A475MEAAD")
    (property "Manufacturer" "Murata")
    (property "Sheetfile" "debug.kicad_sch")
    (property "Sheetname" "Debug and JTAG")
    (property "Val" "4u7")
    (property "Voltage" "")
    (property "ki_description" " ")
    (attr smd)
    (fp_text reference "C150" (at -3.725 -0.32) (layer "B.SilkS")
        (effects (font (size 0.7 0.7) (thickness 0.15)) (justify left bottom mirror))
    )
    (fp_text value "C_4u7_0402" (at 0 -1.4) (layer "B.Fab") hide
        (effects (font (size 0.7 0.7) (thickness 0.15)) (justify left bottom mirror))
    )
    (fp_text user "Author: Antmicro" (at -0.932 -4.17) (layer "B.Fab") hide
        (effects (font (size 0.7 0.7) (thickness 0.15)) (justify left bottom mirror))
    )
    (fp_text user "License: Apache-2.0" (at -0.932 -5.17) (layer "B.Fab") hide
        (effects (font (size 0.7 0.7) (thickness 0.15)) (justify left bottom mirror))
    )
    (fp_text user "${REFERENCE}" (at -0.932 -3.168) (layer "B.Fab") hide
        (effects (font (size 0.7 0.7) (thickness 0.15)) (justify left bottom mirror))
    )
    (fp_rect (start -0.94 0.47) (end 0.94 -0.47)
      (stroke (width 0.05) (type solid)) (fill none) (layer "B.CrtYd"))
    (fp_rect (start -0.499 0.249) (end 0.499 -0.249)
      (stroke (width 0.15) (type solid)) (fill none) (layer "B.Fab"))
    (pad "1" smd roundrect (at -0.484 0 180) (size 0.59 0.64) (layers "B.Cu" "B.Paste" "B.Mask") (roundrect_rratio 0.25)
      (net 1 "GND") (pintype "passive"))
    (pad "2" smd roundrect (at 0.484 0 180) (size 0.59 0.64) (layers "B.Cu" "B.Paste" "B.Mask") (roundrect_rratio 0.25)
      (net 138 "/Debug and JTAG/USB_3V3") (pintype "passive"))
  )
)
